(kicad_pcb
	(version 20260206)
	(generator "pcbnew")
	(generator_version "10.0")
	(general
		(thickness 1.6)
		(legacy_teardrops no)
	)
	(paper "A4")
	(title_block
		(title "Wiwynn_Tioga_Pass_MB.brd")
		(comment 1 "Tioga Pass / footprint 190 of 4770 (U2D1), pads 411-520 of 3647")
	)
	(layers
		(0 "F.Cu" signal "TOP")
		(4 "In1.Cu" signal "L2GND")
		(6 "In2.Cu" signal "L3")
		(8 "In3.Cu" signal "L4GND")
		(10 "In4.Cu" signal "L5")
		(12 "In5.Cu" signal "L6GND")
		(14 "In6.Cu" signal "L7VCC")
		(16 "In7.Cu" signal "L8VCC")
		(18 "In8.Cu" signal "L9GND")
		(20 "In9.Cu" signal "L10")
		(22 "In10.Cu" signal "L11GND")
		(24 "In11.Cu" signal "L12")
		(26 "In12.Cu" signal "L13GND")
		(2 "B.Cu" signal "BOTTOM")
		(9 "F.Adhes" user "F.Adhesive")
		(11 "B.Adhes" user "B.Adhesive")
		(13 "F.Paste" user "Package Geometry/Pastemask Top")
		(15 "B.Paste" user "Package Geometry/Pastemask Bottom")
		(5 "F.SilkS" user "Ref Des/Silkscreen Top")
		(7 "B.SilkS" user "Ref Des/Silkscreen Bottom")
		(1 "F.Mask" user "Board Geometry/Soldermask Top")
		(3 "B.Mask" user "Board Geometry/Soldermask Bottom")
		(17 "Dwgs.User" user "User.Drawings")
		(19 "Cmts.User" user "User.Comments")
		(21 "Eco1.User" user "User.Eco1")
		(23 "Eco2.User" user "User.Eco2")
		(25 "Edge.Cuts" user "Board Geometry/Outline")
		(27 "Margin" user)
		(31 "F.CrtYd" user "Package Geometry/Place Bound Top")
		(29 "B.CrtYd" user "Package Geometry/Place Bound Bottom")
		(35 "F.Fab" user "Ref Des/Assembly Top")
		(33 "B.Fab" user "Ref Des/Assembly Bottom")
	)
	(footprint ""
		(layer "F.Cu")
		(at 104.99979 -76.550012 180)
		(property "Reference" "U2D1"
			(at 25.19299 30.484318 0)
			(unlocked yes)
			(layer "F.SilkS")
			(effects
				(font
					(size 0.7874 0.5842)
					(thickness 0.1524)
				)
			)
		)
		(property "Value" ""
			(at 0 0 180)
			(layer "F.Fab")
			(effects
				(font
					(size 1.27 1.27)
				)
			)
		)
		(duplicate_pad_numbers_are_jumpers no)
		(pad "AK49" smd circle
			(at 5.485892 -12.539726)
			(size 0.4318 0.4318)
			(layers "F.Cu" "F.Mask" "F.Paste")
			(net "PVCCIN_CPU1")
		)
		(pad "AK51" smd circle
			(at 7.202932 -12.539726)
			(size 0.4318 0.4318)
			(layers "F.Cu" "F.Mask" "F.Paste")
			(net "PVCCIN_CPU1")
		)
		(pad "AK53" smd circle
			(at 8.919972 -12.539726)
			(size 0.4318 0.4318)
			(layers "F.Cu" "F.Mask" "F.Paste")
			(net "PVCCIN_CPU1")
		)
		(pad "AK55" smd circle
			(at 10.637012 -12.539726)
			(size 0.4318 0.4318)
			(layers "F.Cu" "F.Mask" "F.Paste")
			(net "GND")
		)
		(pad "AK57" smd circle
			(at 12.354052 -12.539726)
			(size 0.4318 0.4318)
			(layers "F.Cu" "F.Mask" "F.Paste")
			(net "TP_CPU1_RSVD_219")
		)
		(pad "AK59" smd circle
			(at 14.071092 -12.539726)
			(size 0.4318 0.4318)
			(layers "F.Cu" "F.Mask" "F.Paste")
			(net "TP_CPU1_RSVD_218")
		)
		(pad "AK61" smd circle
			(at 15.787878 -12.539726)
			(size 0.4318 0.4318)
			(layers "F.Cu" "F.Mask" "F.Paste")
			(net "TP_CPU1_RSVD_217")
		)
		(pad "AK63" smd circle
			(at 17.504918 -12.539726)
			(size 0.4318 0.4318)
			(layers "F.Cu" "F.Mask" "F.Paste")
			(net "M_H_CPU_VREF")
		)
		(pad "AK65" smd circle
			(at 19.221958 -12.539726)
			(size 0.4318 0.4318)
			(layers "F.Cu" "F.Mask" "F.Paste")
			(net "GND")
		)
		(pad "AK67" smd circle
			(at 20.938998 -12.539726)
			(size 0.4318 0.4318)
			(layers "F.Cu" "F.Mask" "F.Paste")
			(net "GND")
		)
		(pad "AK69" smd circle
			(at 22.656038 -12.539726)
			(size 0.4318 0.4318)
			(layers "F.Cu" "F.Mask" "F.Paste")
			(net "TP_CPU1_RSVD_216")
		)
		(pad "AK73" smd circle
			(at 26.090118 -12.539726)
			(size 0.4318 0.4318)
			(layers "F.Cu" "F.Mask" "F.Paste")
			(net "GND")
		)
		(pad "AK75" smd circle
			(at 27.806904 -12.539726)
			(size 0.4318 0.4318)
			(layers "F.Cu" "F.Mask" "F.Paste")
			(net "M_J_DQ<7>")
		)
		(pad "AK77" smd circle
			(at 29.523944 -12.539726)
			(size 0.4318 0.4318)
			(layers "F.Cu" "F.Mask" "F.Paste")
			(net "M_J_DQ<2>")
		)
		(pad "AK79" smd circle
			(at 31.240984 -12.539726)
			(size 0.4318 0.4318)
			(layers "F.Cu" "F.Mask" "F.Paste")
			(net "GND")
		)
		(pad "AK81" smd circle
			(at 32.958024 -12.539726)
			(size 0.4318 0.4318)
			(layers "F.Cu" "F.Mask" "F.Paste")
			(net "GND")
		)
		(pad "AK83" smd circle
			(at 34.675064 -12.539726)
			(size 0.4318 0.4318)
			(layers "F.Cu" "F.Mask" "F.Paste")
			(net "GND")
		)
		(pad "AK85" smd circle
			(at 36.392104 -12.539726)
			(size 0.4318 0.4318)
			(layers "F.Cu" "F.Mask" "F.Paste")
			(net "GND")
		)
		(pad "AL2" smd circle
			(at -36.392104 -10.244074)
			(size 0.4318 0.4318)
			(layers "F.Cu" "F.Mask" "F.Paste")
			(net "UPI_CPU1_CPU0_P0P0_DN<9>")
		)
		(pad "AL4" smd circle
			(at -34.675064 -10.244074)
			(size 0.4318 0.4318)
			(layers "F.Cu" "F.Mask" "F.Paste")
			(net "GND")
		)
		(pad "AL6" smd circle
			(at -32.958024 -10.244074)
			(size 0.4318 0.4318)
			(layers "F.Cu" "F.Mask" "F.Paste")
			(net "UPI_CPU0_CPU1_P0P0_DP<7>")
		)
		(pad "AL8" smd circle
			(at -31.240984 -10.244074)
			(size 0.4318 0.4318)
			(layers "F.Cu" "F.Mask" "F.Paste")
			(net "UPI_CPU0_CPU1_P0P0_DN<9>")
		)
		(pad "AL10" smd circle
			(at -29.523944 -10.244074)
			(size 0.4318 0.4318)
			(layers "F.Cu" "F.Mask" "F.Paste")
			(net "GND")
		)
		(pad "AL12" smd circle
			(at -27.806904 -10.244074)
			(size 0.4318 0.4318)
			(layers "F.Cu" "F.Mask" "F.Paste")
			(net "H_CPU1_ERR2_G_N")
		)
		(pad "AL14" smd circle
			(at -26.090118 -10.244074)
			(size 0.4318 0.4318)
			(layers "F.Cu" "F.Mask" "F.Paste")
			(net "H_CPU1_CATERR_G_N")
		)
		(pad "AL18" smd circle
			(at -22.656038 -10.244074)
			(size 0.4318 0.4318)
			(layers "F.Cu" "F.Mask" "F.Paste")
			(net "SMB_CPU1_PE_HP_GTL_SDA")
		)
		(pad "AL20" smd circle
			(at -20.938998 -10.244074)
			(size 0.4318 0.4318)
			(layers "F.Cu" "F.Mask" "F.Paste")
			(net "VSENSE_P1V8MCP_CPU1_SKT_VRTN")
		)
		(pad "AL22" smd circle
			(at -19.221958 -10.244074)
			(size 0.4318 0.4318)
			(layers "F.Cu" "F.Mask" "F.Paste")
			(net "TP_CPU1_RSVD_214")
		)
		(pad "AL24" smd circle
			(at -17.504918 -10.244074)
			(size 0.4318 0.4318)
			(layers "F.Cu" "F.Mask" "F.Paste")
			(net "GND")
		)
		(pad "AL26" smd circle
			(at -15.787878 -10.244074)
			(size 0.4318 0.4318)
			(layers "F.Cu" "F.Mask" "F.Paste")
			(net "CLK_322M_OSC_CPU1_RC_DN")
		)
		(pad "AL28" smd circle
			(at -14.071092 -10.244074)
			(size 0.4318 0.4318)
			(layers "F.Cu" "F.Mask" "F.Paste")
			(net "PVCCIO_CPU1")
		)
		(pad "AL30" smd circle
			(at -12.354052 -10.244074)
			(size 0.4318 0.4318)
			(layers "F.Cu" "F.Mask" "F.Paste")
			(net "GND")
		)
		(pad "AL32" smd circle
			(at -10.637012 -10.244074)
			(size 0.4318 0.4318)
			(layers "F.Cu" "F.Mask" "F.Paste")
			(net "GND")
		)
		(pad "AL34" smd circle
			(at -8.919972 -10.244074)
			(size 0.4318 0.4318)
			(layers "F.Cu" "F.Mask" "F.Paste")
			(net "PVCCIN_CPU1")
		)
		(pad "AL46" smd circle
			(at 2.910586 -12.044172)
			(size 0.508 0.508)
			(layers "F.Cu" "F.Mask" "F.Paste")
			(net "PVCCIN_CPU1")
		)
		(pad "AL48" smd circle
			(at 4.627626 -12.044172)
			(size 0.508 0.508)
			(layers "F.Cu" "F.Mask" "F.Paste")
			(net "PVCCIN_CPU1")
		)
		(pad "AL50" smd circle
			(at 6.344412 -12.044172)
			(size 0.508 0.508)
			(layers "F.Cu" "F.Mask" "F.Paste")
			(net "PVCCIN_CPU1")
		)
		(pad "AL52" smd circle
			(at 8.061452 -12.044172)
			(size 0.508 0.508)
			(layers "F.Cu" "F.Mask" "F.Paste")
			(net "PVCCIN_CPU1")
		)
		(pad "AL54" smd circle
			(at 9.778492 -12.044172)
			(size 0.4318 0.4318)
			(layers "F.Cu" "F.Mask" "F.Paste")
			(net "PVCCIN_CPU1")
		)
		(pad "AL56" smd circle
			(at 11.495532 -12.044172)
			(size 0.4318 0.4318)
			(layers "F.Cu" "F.Mask" "F.Paste")
			(net "GND")
		)
		(pad "AL58" smd circle
			(at 13.212572 -12.044172)
			(size 0.4318 0.4318)
			(layers "F.Cu" "F.Mask" "F.Paste")
			(net "TP_CPU1_RSVD_212")
		)
		(pad "AL60" smd circle
			(at 14.929612 -12.044172)
			(size 0.4318 0.4318)
			(layers "F.Cu" "F.Mask" "F.Paste")
			(net "TP_CPU1_RSVD_211")
		)
		(pad "AL62" smd circle
			(at 16.646398 -12.044172)
			(size 0.4318 0.4318)
			(layers "F.Cu" "F.Mask" "F.Paste")
			(net "TP_CPU1_RSVD_210")
		)
		(pad "AL64" smd circle
			(at 18.363438 -12.044172)
			(size 0.4318 0.4318)
			(layers "F.Cu" "F.Mask" "F.Paste")
			(net "GND")
		)
		(pad "AL66" smd circle
			(at 20.080478 -12.044172)
			(size 0.4318 0.4318)
			(layers "F.Cu" "F.Mask" "F.Paste")
			(net "M_J_DQS_DN<12>")
		)
		(pad "AL68" smd circle
			(at 21.797518 -12.044172)
			(size 0.4318 0.4318)
			(layers "F.Cu" "F.Mask" "F.Paste")
			(net "GND")
		)
		(pad "AL74" smd circle
			(at 26.948384 -12.044172)
			(size 0.4318 0.4318)
			(layers "F.Cu" "F.Mask" "F.Paste")
			(net "M_J_DQS_DN<0>")
		)
		(pad "AL76" smd circle
			(at 28.665424 -12.044172)
			(size 0.4318 0.4318)
			(layers "F.Cu" "F.Mask" "F.Paste")
			(net "GND")
		)
		(pad "AL78" smd circle
			(at 30.382464 -12.044172)
			(size 0.4318 0.4318)
			(layers "F.Cu" "F.Mask" "F.Paste")
			(net "GND")
		)
		(pad "AL80" smd circle
			(at 32.099504 -12.044172)
			(size 0.4318 0.4318)
			(layers "F.Cu" "F.Mask" "F.Paste")
			(net "GND")
		)
		(pad "AL82" smd circle
			(at 33.816544 -12.044172)
			(size 0.4318 0.4318)
			(layers "F.Cu" "F.Mask" "F.Paste")
			(net "GND")
		)
		(pad "AL84" smd circle
			(at 35.533584 -12.044172)
			(size 0.4318 0.4318)
			(layers "F.Cu" "F.Mask" "F.Paste")
			(net "M_G_DQS_DN<9>")
		)
		(pad "AL86" smd custom
			(at 37.250624 -12.044172 270)
			(size 0.10795 0.10795)
			(layers "F.Cu" "F.Mask" "F.Paste")
			(net "GND")
			(options
				(clearance outline)
				(anchor circle)
			)
			(primitives
				(gr_poly
					(pts
						(arc
							(start 0.2159 -0.0381)
							(mid 0 -0.254)
							(end -0.2159 -0.0381)
						)
						(arc
							(start -0.2159 0.0381)
							(mid 0 0.254)
							(end 0.2159 0.0381)
						)
					)
					(width 0)
					(fill yes)
				)
			)
		)
		(pad "AM1" smd custom
			(at -37.250624 -9.749028 90)
			(size 0.10795 0.10795)
			(layers "F.Cu" "F.Mask" "F.Paste")
			(net "GND")
			(options
				(clearance outline)
				(anchor circle)
			)
			(primitives
				(gr_poly
					(pts
						(arc
							(start 0.2159 -0.0381)
							(mid 0 -0.254)
							(end -0.2159 -0.0381)
						)
						(arc
							(start -0.2159 0.0381)
							(mid 0 0.254)
							(end 0.2159 0.0381)
						)
					)
					(width 0)
					(fill yes)
				)
			)
		)
		(pad "AM3" smd circle
			(at -35.533584 -9.749028)
			(size 0.4318 0.4318)
			(layers "F.Cu" "F.Mask" "F.Paste")
			(net "UPI_CPU1_CPU0_P0P0_DP<10>")
		)
		(pad "AM5" smd circle
			(at -33.816544 -9.749028)
			(size 0.4318 0.4318)
			(layers "F.Cu" "F.Mask" "F.Paste")
			(net "PVCCIO_CPU1")
		)
		(pad "AM7" smd circle
			(at -32.099504 -9.749028)
			(size 0.4318 0.4318)
			(layers "F.Cu" "F.Mask" "F.Paste")
			(net "UPI_CPU0_CPU1_P0P0_DN<8>")
		)
		(pad "AM9" smd circle
			(at -30.382464 -9.749028)
			(size 0.4318 0.4318)
			(layers "F.Cu" "F.Mask" "F.Paste")
			(net "UPI_CPU0_CPU1_P0P0_DP<9>")
		)
		(pad "AM11" smd circle
			(at -28.665424 -9.749028)
			(size 0.4318 0.4318)
			(layers "F.Cu" "F.Mask" "F.Paste")
			(net "PU_CPU1_TSC_SYNC")
		)
		(pad "AM13" smd circle
			(at -26.948384 -9.749028)
			(size 0.4318 0.4318)
			(layers "F.Cu" "F.Mask" "F.Paste")
			(net "TP_CPU1_RSVD_TEST_3")
		)
		(pad "AM19" smd circle
			(at -21.797518 -9.749028)
			(size 0.4318 0.4318)
			(layers "F.Cu" "F.Mask" "F.Paste")
			(net "SMB_CPU1_PE_HP_GTL_SCL")
		)
		(pad "AM21" smd circle
			(at -20.080478 -9.749028)
			(size 0.4318 0.4318)
			(layers "F.Cu" "F.Mask" "F.Paste")
			(net "PVCCMCP_CPU1")
		)
		(pad "AM23" smd circle
			(at -18.363438 -9.749028)
			(size 0.4318 0.4318)
			(layers "F.Cu" "F.Mask" "F.Paste")
			(net "TP_CPU1_RSVD_208")
		)
		(pad "AM25" smd circle
			(at -16.646398 -9.749028)
			(size 0.4318 0.4318)
			(layers "F.Cu" "F.Mask" "F.Paste")
			(net "PVCCMCP_CPU1")
		)
		(pad "AM27" smd circle
			(at -14.929612 -9.749028)
			(size 0.4318 0.4318)
			(layers "F.Cu" "F.Mask" "F.Paste")
			(net "CLK_100M_CPU1_RC_REFCLK0_DP")
		)
		(pad "AM29" smd circle
			(at -13.212572 -9.749028)
			(size 0.4318 0.4318)
			(layers "F.Cu" "F.Mask" "F.Paste")
			(net "PVCCIO_CPU1")
		)
		(pad "AM31" smd circle
			(at -11.495532 -9.749028)
			(size 0.4318 0.4318)
			(layers "F.Cu" "F.Mask" "F.Paste")
			(net "GND")
		)
		(pad "AM33" smd circle
			(at -9.778492 -9.749028)
			(size 0.4318 0.4318)
			(layers "F.Cu" "F.Mask" "F.Paste")
			(net "PVCCIN_CPU1")
		)
		(pad "AM53" smd circle
			(at 8.919972 -11.549126)
			(size 0.508 0.508)
			(layers "F.Cu" "F.Mask" "F.Paste")
			(net "PVCCIN_CPU1")
		)
		(pad "AM55" smd circle
			(at 10.637012 -11.549126)
			(size 0.4318 0.4318)
			(layers "F.Cu" "F.Mask" "F.Paste")
			(net "PVCCIN_CPU1")
		)
		(pad "AM57" smd circle
			(at 12.354052 -11.549126)
			(size 0.4318 0.4318)
			(layers "F.Cu" "F.Mask" "F.Paste")
			(net "GND")
		)
		(pad "AM59" smd circle
			(at 14.071092 -11.549126)
			(size 0.4318 0.4318)
			(layers "F.Cu" "F.Mask" "F.Paste")
			(net "TP_CPU1_RSVD_205")
		)
		(pad "AM61" smd circle
			(at 15.787878 -11.549126)
			(size 0.4318 0.4318)
			(layers "F.Cu" "F.Mask" "F.Paste")
			(net "TP_CPU1_RSVD_204")
		)
		(pad "AM63" smd circle
			(at 17.504918 -11.549126)
			(size 0.4318 0.4318)
			(layers "F.Cu" "F.Mask" "F.Paste")
			(net "GND")
		)
		(pad "AM65" smd circle
			(at 19.221958 -11.549126)
			(size 0.4318 0.4318)
			(layers "F.Cu" "F.Mask" "F.Paste")
			(net "M_J_DQ<30>")
		)
		(pad "AM67" smd circle
			(at 20.938998 -11.549126)
			(size 0.4318 0.4318)
			(layers "F.Cu" "F.Mask" "F.Paste")
			(net "M_J_DQ<24>")
		)
		(pad "AM69" smd circle
			(at 22.656038 -11.549126)
			(size 0.4318 0.4318)
			(layers "F.Cu" "F.Mask" "F.Paste")
			(net "GND")
		)
		(pad "AM73" smd circle
			(at 26.090118 -11.549126)
			(size 0.4318 0.4318)
			(layers "F.Cu" "F.Mask" "F.Paste")
			(net "GND")
		)
		(pad "AM75" smd circle
			(at 27.806904 -11.549126)
			(size 0.4318 0.4318)
			(layers "F.Cu" "F.Mask" "F.Paste")
			(net "M_J_DQS_DP<0>")
		)
		(pad "AM77" smd circle
			(at 29.523944 -11.549126)
			(size 0.4318 0.4318)
			(layers "F.Cu" "F.Mask" "F.Paste")
			(net "M_J_DQ<6>")
		)
		(pad "AM79" smd circle
			(at 31.240984 -11.549126)
			(size 0.4318 0.4318)
			(layers "F.Cu" "F.Mask" "F.Paste")
			(net "GND")
		)
		(pad "AM81" smd circle
			(at 32.958024 -11.549126)
			(size 0.4318 0.4318)
			(layers "F.Cu" "F.Mask" "F.Paste")
			(net "M_H_DQ<3>")
		)
		(pad "AM83" smd circle
			(at 34.675064 -11.549126)
			(size 0.4318 0.4318)
			(layers "F.Cu" "F.Mask" "F.Paste")
			(net "GND")
		)
		(pad "AM85" smd circle
			(at 36.392104 -11.549126)
			(size 0.4318 0.4318)
			(layers "F.Cu" "F.Mask" "F.Paste")
			(net "M_G_DQS_DP<9>")
		)
		(pad "AN2" smd circle
			(at -36.392104 -9.253474)
			(size 0.4318 0.4318)
			(layers "F.Cu" "F.Mask" "F.Paste")
			(net "GND")
		)
		(pad "AN4" smd circle
			(at -34.675064 -9.253474)
			(size 0.4318 0.4318)
			(layers "F.Cu" "F.Mask" "F.Paste")
			(net "UPI_CPU1_CPU0_P0P0_DP<11>")
		)
		(pad "AN6" smd circle
			(at -32.958024 -9.253474)
			(size 0.4318 0.4318)
			(layers "F.Cu" "F.Mask" "F.Paste")
			(net "GND")
		)
		(pad "AN8" smd circle
			(at -31.240984 -9.253474)
			(size 0.4318 0.4318)
			(layers "F.Cu" "F.Mask" "F.Paste")
			(net "UPI_CPU0_CPU1_P0P0_DP<10>")
		)
		(pad "AN10" smd circle
			(at -29.523944 -9.253474)
			(size 0.4318 0.4318)
			(layers "F.Cu" "F.Mask" "F.Paste")
			(net "PVCCIO_CPU1")
		)
		(pad "AN12" smd circle
			(at -27.806904 -9.253474)
			(size 0.4318 0.4318)
			(layers "F.Cu" "F.Mask" "F.Paste")
			(net "TP_CPU1_RSVD_TEST_4")
		)
		(pad "AN14" smd circle
			(at -26.090118 -9.253474)
			(size 0.4318 0.4318)
			(layers "F.Cu" "F.Mask" "F.Paste")
			(net "TP_CPU1_RSVD_TEST_5")
		)
		(pad "AN18" smd circle
			(at -22.656038 -9.253474)
			(size 0.4318 0.4318)
			(layers "F.Cu" "F.Mask" "F.Paste")
			(net "PVCCMCP_CPU1")
		)
		(pad "AN20" smd circle
			(at -20.938998 -9.253474)
			(size 0.4318 0.4318)
			(layers "F.Cu" "F.Mask" "F.Paste")
			(net "H_CPU1_MSMI_G_N")
		)
		(pad "AN22" smd circle
			(at -19.221958 -9.253474)
			(size 0.4318 0.4318)
			(layers "F.Cu" "F.Mask" "F.Paste")
			(net "PVCCMCP_CPU1")
		)
		(pad "AN24" smd circle
			(at -17.504918 -9.253474)
			(size 0.4318 0.4318)
			(layers "F.Cu" "F.Mask" "F.Paste")
			(net "PVCCMCP_CPU1")
		)
		(pad "AN26" smd circle
			(at -15.787878 -9.253474)
			(size 0.4318 0.4318)
			(layers "F.Cu" "F.Mask" "F.Paste")
			(net "PVCCMCP_CPU1")
		)
		(pad "AN28" smd circle
			(at -14.071092 -9.253474)
			(size 0.4318 0.4318)
			(layers "F.Cu" "F.Mask" "F.Paste")
			(net "GND")
		)
		(pad "AN30" smd circle
			(at -12.354052 -9.253474)
			(size 0.4318 0.4318)
			(layers "F.Cu" "F.Mask" "F.Paste")
			(net "PWRGD_CPU1_DRAMPWROK_GHJ_G")
		)
		(pad "AN32" smd circle
			(at -10.637012 -9.253474)
			(size 0.4318 0.4318)
			(layers "F.Cu" "F.Mask" "F.Paste")
			(net "PVCCIN_CPU1")
		)
		(pad "AN54" smd circle
			(at 9.778492 -11.053572)
			(size 0.508 0.508)
			(layers "F.Cu" "F.Mask" "F.Paste")
			(net "PVCCIN_CPU1")
		)
		(pad "AN56" smd circle
			(at 11.495532 -11.053572)
			(size 0.4318 0.4318)
			(layers "F.Cu" "F.Mask" "F.Paste")
			(net "PVCCIN_CPU1")
		)
		(pad "AN58" smd circle
			(at 13.212572 -11.053572)
			(size 0.4318 0.4318)
			(layers "F.Cu" "F.Mask" "F.Paste")
			(net "GND")
		)
		(pad "AN60" smd circle
			(at 14.929612 -11.053572)
			(size 0.4318 0.4318)
			(layers "F.Cu" "F.Mask" "F.Paste")
			(net "TP_CPU1_RSVD_199")
		)
		(pad "AN62" smd circle
			(at 16.646398 -11.053572)
			(size 0.4318 0.4318)
			(layers "F.Cu" "F.Mask" "F.Paste")
			(net "TP_CPU1_RSVD_198")
		)
		(pad "AN64" smd circle
			(at 18.363438 -11.053572)
			(size 0.4318 0.4318)
			(layers "F.Cu" "F.Mask" "F.Paste")
			(net "M_J_DQ<26>")
		)
		(pad "AN66" smd circle
			(at 20.080478 -11.053572)
			(size 0.4318 0.4318)
			(layers "F.Cu" "F.Mask" "F.Paste")
			(net "M_J_DQS_DP<12>")
		)
		(pad "AN68" smd circle
			(at 21.797518 -11.053572)
			(size 0.4318 0.4318)
			(layers "F.Cu" "F.Mask" "F.Paste")
			(net "M_J_DQ<28>")
		)
		(pad "AN74" smd circle
			(at 26.948384 -11.053572)
			(size 0.4318 0.4318)
			(layers "F.Cu" "F.Mask" "F.Paste")
			(net "M_J_DQ<1>")
		)
		(pad "AN76" smd circle
			(at 28.665424 -11.053572)
			(size 0.4318 0.4318)
			(layers "F.Cu" "F.Mask" "F.Paste")
			(net "M_J_DQS_DP<9>")
		)
		(pad "AN78" smd circle
			(at 30.382464 -11.053572)
			(size 0.4318 0.4318)
			(layers "F.Cu" "F.Mask" "F.Paste")
			(net "GND")
		)
	)
)
